# TIMECARD (Time Appliance Project (Time Card)) — schematic netlist excerpt (pin names and nets, part order shuffled) for the footprints in the layout excerpt that follows; sources: Cadence DE-HDL packaged netlist, KiCad conversion of R4006-B0001-02_R01.brd

U1  MP5022CGQV_Z_QFN22  pkg QFN26_118X197_P197_TR049X010  page 27
  EN  = XP12R0V_A_EN
  LOADEN  = UNNAMED_15_MP5022CGQVZQFN22_I_2
  ENTM  = UNNAMED_15_MP5022CGQVZQFN22_I21
  TIMER  = XP12R0V_A_TIMER
  ISET  = XP12R0V_A_ISET
  SS  = XP12R0V_A_SS
  GND  = SG
  IMON  = XP12R0V_A_IMON
  FLTB  = XP12R0V_A_FLTB
  PG  = XP12R0V_A_PG
  OV  = XP12R0V_A_OV
  AVIN  = XP12R0V_A_AVIN
  VOUT_1  = XP12R0V
  VOUT_2  = XP12R0V
  VOUT_3  = XP12R0V
  VOUT_4  = XP12R0V
  VOUT_5  = XP12R0V
  VOUT_6  = XP12R0V
  VOUT_7  = XP12R0V
  VOUT_8  = XP12R0V
  VIN_1  = XP12R0V_IN
  VIN_2  = XP12R0V_IN
  VIN_3  = XP12R0V_IN
  VIN_4  = XP12R0V_IN
  VIN_5  = XP12R0V_IN
  VIN_6  = XP12R0V_IN

(kicad_pcb
	(version 20260206)
	(generator "pcbnew")
	(generator_version "10.0")
	(general
		(thickness 1.6)
		(legacy_teardrops no)
	)
	(paper "A4")
	(title_block
		(title "timecard-production-celestica-r4006 — R4006-B0001-02_R01.brd")
		(comment 1 "Time Appliance Project (Time Card) / footprint 404 of 1113 (U1), pads 1-26 of 26")
	)
	(layers
		(0 "F.Cu" signal "TOP")
		(4 "In1.Cu" signal "L02_GND1")
		(6 "In2.Cu" signal "L03_SIG1")
		(8 "In3.Cu" signal "L04_GND2")
		(10 "In4.Cu" signal "L05_VCC1")
		(12 "In5.Cu" signal "L06_VCC2")
		(14 "In6.Cu" signal "L07_GND3")
		(16 "In7.Cu" signal "L08_SIG2")
		(18 "In8.Cu" signal "L09_GND4")
		(2 "B.Cu" signal "BOTTOM")
		(9 "F.Adhes" user "F.Adhesive")
		(11 "B.Adhes" user "B.Adhesive")
		(13 "F.Paste" user "Package Geometry/Pastemask Top")
		(15 "B.Paste" user "Package Geometry/Pastemask Bottom")
		(5 "F.SilkS" user "Ref Des/Silkscreen Top")
		(7 "B.SilkS" user "Ref Des/Silkscreen Bottom")
		(1 "F.Mask" user "Board Geometry/Soldermask Top")
		(3 "B.Mask" user "Board Geometry/Soldermask Bottom")
		(17 "Dwgs.User" user "User.Drawings")
		(19 "Cmts.User" user "User.Comments")
		(21 "Eco1.User" user "User.Eco1")
		(23 "Eco2.User" user "User.Eco2")
		(25 "Edge.Cuts" user "Board Geometry/Outline")
		(27 "Margin" user)
		(31 "F.CrtYd" user "Package Geometry/Place Bound Top")
		(29 "B.CrtYd" user "Package Geometry/Place Bound Bottom")
		(35 "F.Fab" user "Ref Des/Assembly Top")
		(33 "B.Fab" user "Ref Des/Assembly Bottom")
	)
	(footprint ""
		(layer "F.Cu")
		(at 140.6144 -94.9198 180)
		(property "Reference" "U1"
			(at 3.0734 0.29083 0)
			(unlocked yes)
			(layer "F.SilkS")
			(effects
				(font
					(size 0.7874 0.5842)
					(thickness 0.1524)
				)
			)
		)
		(property "Value" ""
			(at 0 0 180)
			(layer "F.Fab")
			(effects
				(font
					(size 1.27 1.27)
				)
			)
		)
		(property "Device Type" "MP5022CGQV_Z_QFN22-G220-10510-A"
			(at 0.130556 4.082542 180)
			(unlocked yes)
			(layer "F.Fab")
			(hide yes)
			(effects
				(font
					(size 0.7874 0.5842)
					(thickness 0.1524)
				)
			)
		)
		(property "User Part Number" "PARTNUM*"
			(at 0.022352 5.136896 180)
			(unlocked yes)
			(layer "Cmts.User")
			(hide yes)
			(effects
				(font
					(size 0.7874 0.5842)
					(thickness 0.1524)
				)
			)
		)
		(duplicate_pad_numbers_are_jumpers no)
		(pad "1" smd rect
			(at -1.440434 -1.999996 180)
			(size 1.1938 0.3048)
			(layers "F.Cu" "F.Mask" "F.Paste")
			(net "XP12R0V_A_EN")
		)
		(pad "2" smd rect
			(at -1.440434 -1.500124 180)
			(size 1.1938 0.3048)
			(layers "F.Cu" "F.Mask" "F.Paste")
			(net "UNNAMED_15_MP5022CGQVZQFN22_I_2")
		)
		(pad "3" smd rect
			(at -1.440434 -0.999998 180)
			(size 1.1938 0.3048)
			(layers "F.Cu" "F.Mask" "F.Paste")
			(net "UNNAMED_15_MP5022CGQVZQFN22_I21")
		)
		(pad "4" smd rect
			(at -1.440434 -0.500126 180)
			(size 1.1938 0.3048)
			(layers "F.Cu" "F.Mask" "F.Paste")
			(net "XP12R0V_A_TIMER")
		)
		(pad "5" smd rect
			(at -1.440434 0 180)
			(size 1.1938 0.3048)
			(layers "F.Cu" "F.Mask" "F.Paste")
			(net "XP12R0V_A_ISET")
		)
		(pad "6" smd rect
			(at -1.440434 0.500126 180)
			(size 1.1938 0.3048)
			(layers "F.Cu" "F.Mask" "F.Paste")
			(net "XP12R0V_A_SS")
		)
		(pad "7" smd rect
			(at -1.440434 0.999998 180)
			(size 1.1938 0.3048)
			(layers "F.Cu" "F.Mask" "F.Paste")
			(net "SG")
		)
		(pad "8" smd rect
			(at -1.440434 1.500124 180)
			(size 1.1938 0.3048)
			(layers "F.Cu" "F.Mask" "F.Paste")
			(net "XP12R0V_A_IMON")
		)
		(pad "9" smd rect
			(at -1.440434 1.999996 180)
			(size 1.1938 0.3048)
			(layers "F.Cu" "F.Mask" "F.Paste")
			(net "XP12R0V_A_FLTB")
		)
		(pad "10" smd rect
			(at -0.500126 2.478024 180)
			(size 0.3302 1.1176)
			(layers "F.Cu" "F.Mask" "F.Paste")
			(net "XP12R0V_A_PG")
		)
		(pad "11" smd rect
			(at 0.500126 2.478024 180)
			(size 0.3302 1.1176)
			(layers "F.Cu" "F.Mask" "F.Paste")
			(net "XP12R0V_A_OV")
		)
		(pad "12" smd rect
			(at 1.440434 1.999996 180)
			(size 1.1938 0.3048)
			(layers "F.Cu" "F.Mask" "F.Paste")
			(net "XP12R0V_A_AVIN")
		)
		(pad "13" smd rect
			(at 1.440434 1.500124 180)
			(size 1.1938 0.3048)
			(layers "F.Cu" "F.Mask" "F.Paste")
			(net "XP12R0V")
		)
		(pad "14" smd rect
			(at 1.440434 0.999998 180)
			(size 1.1938 0.3048)
			(layers "F.Cu" "F.Mask" "F.Paste")
			(net "XP12R0V")
		)
		(pad "15" smd rect
			(at 1.440434 0.500126 180)
			(size 1.1938 0.3048)
			(layers "F.Cu" "F.Mask" "F.Paste")
			(net "XP12R0V")
		)
		(pad "16" smd rect
			(at 1.440434 0 180)
			(size 1.1938 0.3048)
			(layers "F.Cu" "F.Mask" "F.Paste")
			(net "XP12R0V")
		)
		(pad "17" smd rect
			(at 1.440434 -0.500126 180)
			(size 1.1938 0.3048)
			(layers "F.Cu" "F.Mask" "F.Paste")
			(net "XP12R0V")
		)
		(pad "18" smd rect
			(at 1.440434 -0.999998 180)
			(size 1.1938 0.3048)
			(layers "F.Cu" "F.Mask" "F.Paste")
			(net "XP12R0V")
		)
		(pad "19" smd rect
			(at 1.440434 -1.500124 180)
			(size 1.1938 0.3048)
			(layers "F.Cu" "F.Mask" "F.Paste")
			(net "XP12R0V")
		)
		(pad "20" smd rect
			(at 1.440434 -1.999996 180)
			(size 1.1938 0.3048)
			(layers "F.Cu" "F.Mask" "F.Paste")
			(net "XP12R0V")
		)
		(pad "21" smd circle
			(at 0 -2.003298 180)
			(size 0 0)
			(layers "F.Cu" "F.Mask" "F.Paste")
			(net "XP12R0V_IN")
		)
		(pad "22" smd rect
			(at -0.509778 -2.64033 180)
			(size 0.0254 0.0254)
			(layers "F.Cu" "F.Mask" "F.Paste")
			(net "XP12R0V_IN")
		)
		(pad "23" smd rect
			(at 0 -1.100074 180)
			(size 1.2446 0.254)
			(layers "F.Cu" "F.Mask" "F.Paste")
			(net "XP12R0V_IN")
		)
		(pad "24" smd rect
			(at 0 -0.199898 180)
			(size 1.2446 0.254)
			(layers "F.Cu" "F.Mask" "F.Paste")
			(net "XP12R0V_IN")
		)
		(pad "25" smd rect
			(at 0 0.700024 180)
			(size 1.2446 0.254)
			(layers "F.Cu" "F.Mask" "F.Paste")
			(net "XP12R0V_IN")
		)
		(pad "26" smd rect
			(at 0 1.599946 180)
			(size 1.2446 0.254)
			(layers "F.Cu" "F.Mask" "F.Paste")
			(net "XP12R0V_IN")
		)
	)
)
